(kicad_pcb
	(version 20260206)
	(generator "pcbnew")
	(generator_version "10.0")
	(general
		(thickness 1.6)
		(legacy_teardrops no)
	)
	(paper "A4")
	(title_block
		(title "Wiwynn_Tioga_Pass_MB.brd")
		(comment 1 "Tioga Pass / footprints 1828-1834 of 4770")
	)
	(layers
		(0 "F.Cu" signal "TOP")
		(4 "In1.Cu" signal "L2GND")
		(6 "In2.Cu" signal "L3")
		(8 "In3.Cu" signal "L4GND")
		(10 "In4.Cu" signal "L5")
		(12 "In5.Cu" signal "L6GND")
		(14 "In6.Cu" signal "L7VCC")
		(16 "In7.Cu" signal "L8VCC")
		(18 "In8.Cu" signal "L9GND")
		(20 "In9.Cu" signal "L10")
		(22 "In10.Cu" signal "L11GND")
		(24 "In11.Cu" signal "L12")
		(26 "In12.Cu" signal "L13GND")
		(2 "B.Cu" signal "BOTTOM")
		(9 "F.Adhes" user "F.Adhesive")
		(11 "B.Adhes" user "B.Adhesive")
		(13 "F.Paste" user "Package Geometry/Pastemask Top")
		(15 "B.Paste" user "Package Geometry/Pastemask Bottom")
		(5 "F.SilkS" user "Ref Des/Silkscreen Top")
		(7 "B.SilkS" user "Ref Des/Silkscreen Bottom")
		(1 "F.Mask" user "Board Geometry/Soldermask Top")
		(3 "B.Mask" user "Board Geometry/Soldermask Bottom")
		(17 "Dwgs.User" user "User.Drawings")
		(19 "Cmts.User" user "User.Comments")
		(21 "Eco1.User" user "User.Eco1")
		(23 "Eco2.User" user "User.Eco2")
		(25 "Edge.Cuts" user "Board Geometry/Outline")
		(27 "Margin" user)
		(31 "F.CrtYd" user "Package Geometry/Place Bound Top")
		(29 "B.CrtYd" user "Package Geometry/Place Bound Bottom")
		(35 "F.Fab" user "Ref Des/Assembly Top")
		(33 "B.Fab" user "Ref Des/Assembly Bottom")
	)
	(footprint ""
		(layer "F.Cu")
		(at 29.636466 -53.42763 90)
		(property "Reference" "CT24"
			(at 1.67513 -6.1976 0)
			(unlocked yes)
			(layer "F.SilkS")
			(effects
				(font
					(size 0.7874 0.5842)
					(thickness 0.1524)
				)
				(justify left)
			)
		)
		(property "Value" ""
			(at 0 0 90)
			(layer "F.Fab")
			(effects
				(font
					(size 1.27 1.27)
				)
			)
		)
		(duplicate_pad_numbers_are_jumpers no)
		(fp_poly
			(pts
				(xy 0.3048 -0.1016) (xy 0.3048 0.9906) (xy -0.3048 0.9906) (xy -0.3048 -0.1016)
			)
			(stroke
				(width 0)
				(type default)
			)
			(fill no)
			(layer "F.CrtYd")
		)
		(fp_line
			(start 0.3048 -0.1016)
			(end -0.3048 -0.1016)
			(stroke
				(width 0.1)
				(type default)
			)
			(layer "F.Fab")
		)
		(fp_line
			(start -0.3048 -0.1016)
			(end -0.3048 0.9906)
			(stroke
				(width 0.1)
				(type default)
			)
			(layer "F.Fab")
		)
		(fp_line
			(start 0.3048 0.9906)
			(end 0.3048 -0.1016)
			(stroke
				(width 0.1)
				(type default)
			)
			(layer "F.Fab")
		)
		(fp_line
			(start -0.3048 0.9906)
			(end 0.3048 0.9906)
			(stroke
				(width 0.1)
				(type default)
			)
			(layer "F.Fab")
		)
		(pad "1" smd rect
			(at 0 0 90)
			(size 0.508 0.508)
			(layers "F.Cu" "F.Mask" "F.Paste")
			(net "VR_PVCCIN_CPU1_AIREF1")
		)
		(pad "2" smd rect
			(at 0 0.889 90)
			(size 0.508 0.508)
			(layers "F.Cu" "F.Mask" "F.Paste")
			(net "GND")
		)
		(zone
			(layer "F.Cu")
			(hatch none 0.5)
			(connect_pads
				(clearance 0)
			)
			(min_thickness 0.25)
			(keepout
				(tracks allowed)
				(vias not_allowed)
				(pads allowed)
				(copperpour not_allowed)
				(footprints allowed)
			)
			(placement
				(enabled no)
				(sheetname "")
			)
			(fill
				(thermal_gap 0.5)
				(thermal_bridge_width 0.5)
				(island_removal_mode 0)
			)
			(polygon
				(pts
					(xy 29.890466 -53.17363) (xy 29.890466 -53.68163) (xy 30.271466 -53.68163) (xy 30.271466 -53.17363)
				)
			)
		)
		(zone
			(layer "F.Cu")
			(hatch none 0.5)
			(connect_pads
				(clearance 0)
			)
			(min_thickness 0.25)
			(keepout
				(tracks not_allowed)
				(vias allowed)
				(pads allowed)
				(copperpour not_allowed)
				(footprints allowed)
			)
			(placement
				(enabled no)
				(sheetname "")
			)
			(fill
				(thermal_gap 0.5)
				(thermal_bridge_width 0.5)
				(island_removal_mode 0)
			)
			(polygon
				(pts
					(xy 30.271466 -53.17363) (xy 30.271466 -53.68163) (xy 29.890466 -53.68163) (xy 29.890466 -53.17363)
				)
			)
		)
	)
	(footprint ""
		(layer "F.Cu")
		(at 323.0245 -118.415816 -90)
		(property "Reference" "C833"
			(at -0.8382 -0.67818 270)
			(unlocked yes)
			(layer "F.SilkS")
			(effects
				(font
					(size 0.4064 0.254)
					(thickness 0.1524)
				)
				(justify left)
			)
		)
		(property "Value" ""
			(at 0 0 270)
			(layer "F.Fab")
			(effects
				(font
					(size 1.27 1.27)
				)
			)
		)
		(duplicate_pad_numbers_are_jumpers no)
		(fp_poly
			(pts
				(xy 0.3048 -0.1016) (xy 0.3048 0.9906) (xy -0.3048 0.9906) (xy -0.3048 -0.1016)
			)
			(stroke
				(width 0)
				(type default)
			)
			(fill no)
			(layer "F.CrtYd")
		)
		(fp_line
			(start -0.3048 0.9906)
			(end 0.3048 0.9906)
			(stroke
				(width 0.1)
				(type default)
			)
			(layer "F.Fab")
		)
		(fp_line
			(start 0.3048 0.9906)
			(end 0.3048 -0.1016)
			(stroke
				(width 0.1)
				(type default)
			)
			(layer "F.Fab")
		)
		(fp_line
			(start -0.3048 -0.1016)
			(end -0.3048 0.9906)
			(stroke
				(width 0.1)
				(type default)
			)
			(layer "F.Fab")
		)
		(fp_line
			(start 0.3048 -0.1016)
			(end -0.3048 -0.1016)
			(stroke
				(width 0.1)
				(type default)
			)
			(layer "F.Fab")
		)
		(pad "1" smd rect
			(at 0 0 270)
			(size 0.508 0.508)
			(layers "F.Cu" "F.Mask" "F.Paste")
			(net "P3E_CPU0_PE1_PCH_TXP<11>")
		)
		(pad "2" smd rect
			(at 0 0.889 270)
			(size 0.508 0.508)
			(layers "F.Cu" "F.Mask" "F.Paste")
			(net "P3E_CPU0_PE1_PCH_CON_TXP<11>")
		)
		(zone
			(layer "F.Cu")
			(hatch none 0.5)
			(connect_pads
				(clearance 0)
			)
			(min_thickness 0.25)
			(keepout
				(tracks not_allowed)
				(vias allowed)
				(pads allowed)
				(copperpour not_allowed)
				(footprints allowed)
			)
			(placement
				(enabled no)
				(sheetname "")
			)
			(fill
				(thermal_gap 0.5)
				(thermal_bridge_width 0.5)
				(island_removal_mode 0)
			)
			(polygon
				(pts
					(xy 322.3895 -118.669816) (xy 322.3895 -118.161816) (xy 322.7705 -118.161816) (xy 322.7705 -118.669816)
				)
			)
		)
		(zone
			(layer "F.Cu")
			(hatch none 0.5)
			(connect_pads
				(clearance 0)
			)
			(min_thickness 0.25)
			(keepout
				(tracks allowed)
				(vias not_allowed)
				(pads allowed)
				(copperpour not_allowed)
				(footprints allowed)
			)
			(placement
				(enabled no)
				(sheetname "")
			)
			(fill
				(thermal_gap 0.5)
				(thermal_bridge_width 0.5)
				(island_removal_mode 0)
			)
			(polygon
				(pts
					(xy 322.7705 -118.669816) (xy 322.7705 -118.161816) (xy 322.3895 -118.161816) (xy 322.3895 -118.669816)
				)
			)
		)
	)
	(footprint ""
		(layer "F.Cu")
		(at 360.622088 -142.03172 -90)
		(property "Reference" "RF18"
			(at -0.8382 -0.67818 270)
			(unlocked yes)
			(layer "F.SilkS")
			(effects
				(font
					(size 0.4064 0.254)
					(thickness 0.1524)
				)
				(justify left)
			)
		)
		(property "Value" ""
			(at 0 0 270)
			(layer "F.Fab")
			(effects
				(font
					(size 1.27 1.27)
				)
			)
		)
		(duplicate_pad_numbers_are_jumpers no)
		(fp_poly
			(pts
				(xy -0.2794 -0.1016) (xy 0.2794 -0.1016) (xy 0.2794 0.9906) (xy -0.2794 0.9906)
			)
			(stroke
				(width 0)
				(type default)
			)
			(fill no)
			(layer "F.CrtYd")
		)
		(fp_line
			(start -0.2794 0.9906)
			(end 0.2794 0.9906)
			(stroke
				(width 0.1)
				(type default)
			)
			(layer "F.Fab")
		)
		(fp_line
			(start 0.2794 0.9906)
			(end 0.2794 -0.1016)
			(stroke
				(width 0.1)
				(type default)
			)
			(layer "F.Fab")
		)
		(fp_line
			(start -0.2794 -0.1016)
			(end -0.2794 0.9906)
			(stroke
				(width 0.1)
				(type default)
			)
			(layer "F.Fab")
		)
		(fp_line
			(start 0.2794 -0.1016)
			(end -0.2794 -0.1016)
			(stroke
				(width 0.1)
				(type default)
			)
			(layer "F.Fab")
		)
		(pad "1" smd rect
			(at 0 0 270)
			(size 0.508 0.508)
			(layers "F.Cu" "F.Mask" "F.Paste")
			(net "VR_PVDDQ_DEF_AIREF2")
		)
		(pad "2" smd rect
			(at 0 0.889 270)
			(size 0.508 0.508)
			(layers "F.Cu" "F.Mask" "F.Paste")
			(net "ISENSE_PVDDQ_DEF_PH2_IMON")
		)
		(zone
			(layer "F.Cu")
			(hatch none 0.5)
			(connect_pads
				(clearance 0)
			)
			(min_thickness 0.25)
			(keepout
				(tracks not_allowed)
				(vias allowed)
				(pads allowed)
				(copperpour not_allowed)
				(footprints allowed)
			)
			(placement
				(enabled no)
				(sheetname "")
			)
			(fill
				(thermal_gap 0.5)
				(thermal_bridge_width 0.5)
				(island_removal_mode 0)
			)
			(polygon
				(pts
					(xy 359.987088 -142.28572) (xy 359.987088 -141.77772) (xy 360.368088 -141.77772) (xy 360.368088 -142.28572)
				)
			)
		)
		(zone
			(layer "F.Cu")
			(hatch none 0.5)
			(connect_pads
				(clearance 0)
			)
			(min_thickness 0.25)
			(keepout
				(tracks allowed)
				(vias not_allowed)
				(pads allowed)
				(copperpour not_allowed)
				(footprints allowed)
			)
			(placement
				(enabled no)
				(sheetname "")
			)
			(fill
				(thermal_gap 0.5)
				(thermal_bridge_width 0.5)
				(island_removal_mode 0)
			)
			(polygon
				(pts
					(xy 360.368088 -142.28572) (xy 360.368088 -141.77772) (xy 359.987088 -141.77772) (xy 359.987088 -142.28572)
				)
			)
		)
	)
	(footprint ""
		(layer "F.Cu")
		(at 28.380182 -149.7838 -90)
		(property "Reference" "C1A4"
			(at 0 0 270)
			(layer "F.SilkS")
			(hide yes)
			(effects
				(font
					(size 1.27 1.27)
				)
			)
		)
		(property "Value" ""
			(at 0 0 270)
			(layer "F.Fab")
			(effects
				(font
					(size 1.27 1.27)
				)
			)
		)
		(duplicate_pad_numbers_are_jumpers no)
		(fp_poly
			(pts
				(xy -0.7239 -0.2159) (xy 0.7239 -0.2159) (xy 0.7239 1.9939) (xy -0.7239 1.9939)
			)
			(stroke
				(width 0)
				(type default)
			)
			(fill no)
			(layer "F.CrtYd")
		)
		(fp_line
			(start -0.7239 1.9939)
			(end 0.7239 1.9939)
			(stroke
				(width 0.1)
				(type default)
			)
			(layer "F.Fab")
		)
		(fp_line
			(start 0.7239 1.9939)
			(end 0.7239 -0.2159)
			(stroke
				(width 0.1)
				(type default)
			)
			(layer "F.Fab")
		)
		(fp_line
			(start -0.7239 -0.2159)
			(end -0.7239 1.9939)
			(stroke
				(width 0.1)
				(type default)
			)
			(layer "F.Fab")
		)
		(fp_line
			(start 0.7239 -0.2159)
			(end -0.7239 -0.2159)
			(stroke
				(width 0.1)
				(type default)
			)
			(layer "F.Fab")
		)
		(pad "1" smd rect
			(at 0 0 270)
			(size 1.27 1.016)
			(layers "F.Cu" "F.Mask" "F.Paste")
			(net "P12V_NVDIMM_KLM")
		)
		(pad "2" smd rect
			(at 0 1.778 270)
			(size 1.27 1.016)
			(layers "F.Cu" "F.Mask" "F.Paste")
			(net "GND")
		)
		(zone
			(layer "F.Cu")
			(hatch none 0.5)
			(connect_pads
				(clearance 0)
			)
			(min_thickness 0.25)
			(keepout
				(tracks not_allowed)
				(vias allowed)
				(pads allowed)
				(copperpour not_allowed)
				(footprints allowed)
			)
			(placement
				(enabled no)
				(sheetname "")
			)
			(fill
				(thermal_gap 0.5)
				(thermal_bridge_width 0.5)
				(island_removal_mode 0)
			)
			(polygon
				(pts
					(xy 27.872182 -150.4188) (xy 27.872182 -149.1488) (xy 27.110182 -149.1488) (xy 27.110182 -150.4188)
				)
			)
		)
	)
	(footprint ""
		(layer "F.Cu")
		(at 5.909056 2.91846 90)
		(property "Reference" "CF20"
			(at 0 0 90)
			(layer "F.SilkS")
			(hide yes)
			(effects
				(font
					(size 1.27 1.27)
				)
			)
		)
		(property "Value" "*"
			(at 1.1811 -2.8194 90)
			(unlocked yes)
			(layer "F.Fab")
			(hide yes)
			(effects
				(font
					(size 1.27 1.016)
					(thickness 0.1524)
				)
			)
		)
		(property "Device Type" "SC22P50V2JN-4GP_SMD-BCG-SC22P5A"
			(at 1.1811 -4.3434 90)
			(unlocked yes)
			(layer "F.Fab")
			(hide yes)
			(effects
				(font
					(size 1.27 1.016)
					(thickness 0.1524)
				)
			)
		)
		(duplicate_pad_numbers_are_jumpers no)
		(fp_rect
			(start -0.4318 0.9525)
			(end 0.4318 -0.9525)
			(stroke
				(width 0)
				(type default)
			)
			(fill no)
			(layer "F.CrtYd")
		)
		(fp_rect
			(start -0.4318 0.9525)
			(end 0.4318 -0.9525)
			(stroke
				(width 0)
				(type default)
			)
			(fill no)
			(layer "F.Fab")
		)
		(pad "1" smd custom
			(at 0 -0.4445 90)
			(size 0.1524 0.1524)
			(layers "F.Cu" "F.Mask" "F.Paste")
			(net "VR_PVDDQ_GHJ_AIREF2")
			(options
				(clearance outline)
				(anchor circle)
			)
			(primitives
				(gr_poly
					(pts
						(arc
							(start 0.3048 -0.2032)
							(mid 0.275042 -0.275042)
							(end 0.2032 -0.3048)
						)
						(arc
							(start -0.2032 -0.3048)
							(mid -0.275042 -0.275042)
							(end -0.3048 -0.2032)
						)
						(arc
							(start -0.3048 0.2032)
							(mid -0.275042 0.275042)
							(end -0.2032 0.3048)
						)
						(arc
							(start 0.2032 0.3048)
							(mid 0.275042 0.275042)
							(end 0.3048 0.2032)
						)
					)
					(width 0)
					(fill yes)
				)
			)
		)
		(pad "2" smd custom
			(at 0 0.4445 90)
			(size 0.1524 0.1524)
			(layers "F.Cu" "F.Mask" "F.Paste")
			(net "ISENSE_PVDDQ_GHJ_PH2_IMON")
			(options
				(clearance outline)
				(anchor circle)
			)
			(primitives
				(gr_poly
					(pts
						(arc
							(start 0.3048 -0.2032)
							(mid 0.275042 -0.275042)
							(end 0.2032 -0.3048)
						)
						(arc
							(start -0.2032 -0.3048)
							(mid -0.275042 -0.275042)
							(end -0.3048 -0.2032)
						)
						(arc
							(start -0.3048 0.2032)
							(mid -0.275042 0.275042)
							(end -0.2032 0.3048)
						)
						(arc
							(start 0.2032 0.3048)
							(mid 0.275042 0.275042)
							(end 0.3048 0.2032)
						)
					)
					(width 0)
					(fill yes)
				)
			)
		)
	)
	(footprint ""
		(layer "F.Cu")
		(at 364.617 -110.998 90)
		(property "Reference" "C7C1"
			(at 0 0 90)
			(layer "F.SilkS")
			(hide yes)
			(effects
				(font
					(size 1.27 1.27)
				)
			)
		)
		(property "Value" ""
			(at 0 0 90)
			(layer "F.Fab")
			(effects
				(font
					(size 1.27 1.27)
				)
			)
		)
		(duplicate_pad_numbers_are_jumpers no)
		(fp_poly
			(pts
				(xy 0.3048 -0.1016) (xy 0.3048 0.9906) (xy -0.3048 0.9906) (xy -0.3048 -0.1016)
			)
			(stroke
				(width 0)
				(type default)
			)
			(fill no)
			(layer "F.CrtYd")
		)
		(fp_line
			(start 0.3048 -0.1016)
			(end -0.3048 -0.1016)
			(stroke
				(width 0.1)
				(type default)
			)
			(layer "F.Fab")
		)
		(fp_line
			(start -0.3048 -0.1016)
			(end -0.3048 0.9906)
			(stroke
				(width 0.1)
				(type default)
			)
			(layer "F.Fab")
		)
		(fp_line
			(start 0.3048 0.9906)
			(end 0.3048 -0.1016)
			(stroke
				(width 0.1)
				(type default)
			)
			(layer "F.Fab")
		)
		(fp_line
			(start -0.3048 0.9906)
			(end 0.3048 0.9906)
			(stroke
				(width 0.1)
				(type default)
			)
			(layer "F.Fab")
		)
		(pad "1" smd rect
			(at 0 0 90)
			(size 0.508 0.508)
			(layers "F.Cu" "F.Mask" "F.Paste")
			(net "DMI_CPU0_PCH_TX_DN<1>")
		)
		(pad "2" smd rect
			(at 0 0.889 90)
			(size 0.508 0.508)
			(layers "F.Cu" "F.Mask" "F.Paste")
			(net "DMI_CPU0_PCH_TX_C_DN<1>")
		)
		(zone
			(layer "F.Cu")
			(hatch none 0.5)
			(connect_pads
				(clearance 0)
			)
			(min_thickness 0.25)
			(keepout
				(tracks allowed)
				(vias not_allowed)
				(pads allowed)
				(copperpour not_allowed)
				(footprints allowed)
			)
			(placement
				(enabled no)
				(sheetname "")
			)
			(fill
				(thermal_gap 0.5)
				(thermal_bridge_width 0.5)
				(island_removal_mode 0)
			)
			(polygon
				(pts
					(xy 364.871 -110.744) (xy 364.871 -111.252) (xy 365.252 -111.252) (xy 365.252 -110.744)
				)
			)
		)
		(zone
			(layer "F.Cu")
			(hatch none 0.5)
			(connect_pads
				(clearance 0)
			)
			(min_thickness 0.25)
			(keepout
				(tracks not_allowed)
				(vias allowed)
				(pads allowed)
				(copperpour not_allowed)
				(footprints allowed)
			)
			(placement
				(enabled no)
				(sheetname "")
			)
			(fill
				(thermal_gap 0.5)
				(thermal_bridge_width 0.5)
				(island_removal_mode 0)
			)
			(polygon
				(pts
					(xy 365.252 -110.744) (xy 365.252 -111.252) (xy 364.871 -111.252) (xy 364.871 -110.744)
				)
			)
		)
	)
	(footprint ""
		(layer "F.Cu")
		(at 347.599 -93.761306 -90)
		(property "Reference" "C7C11"
			(at 0 0 270)
			(layer "F.SilkS")
			(hide yes)
			(effects
				(font
					(size 1.27 1.27)
				)
			)
		)
		(property "Value" ""
			(at 0 0 270)
			(layer "F.Fab")
			(effects
				(font
					(size 1.27 1.27)
				)
			)
		)
		(duplicate_pad_numbers_are_jumpers no)
		(fp_poly
			(pts
				(xy 0.3048 -0.1016) (xy 0.3048 0.9906) (xy -0.3048 0.9906) (xy -0.3048 -0.1016)
			)
			(stroke
				(width 0)
				(type default)
			)
			(fill no)
			(layer "F.CrtYd")
		)
		(fp_line
			(start -0.3048 0.9906)
			(end 0.3048 0.9906)
			(stroke
				(width 0.1)
				(type default)
			)
			(layer "F.Fab")
		)
		(fp_line
			(start 0.3048 0.9906)
			(end 0.3048 -0.1016)
			(stroke
				(width 0.1)
				(type default)
			)
			(layer "F.Fab")
		)
		(fp_line
			(start -0.3048 -0.1016)
			(end -0.3048 0.9906)
			(stroke
				(width 0.1)
				(type default)
			)
			(layer "F.Fab")
		)
		(fp_line
			(start 0.3048 -0.1016)
			(end -0.3048 -0.1016)
			(stroke
				(width 0.1)
				(type default)
			)
			(layer "F.Fab")
		)
		(pad "1" smd rect
			(at 0 0 270)
			(size 0.508 0.508)
			(layers "F.Cu" "F.Mask" "F.Paste")
			(net "VR_FET_SW_P12V_STBY_PVCCIO_CPU0")
		)
		(pad "2" smd rect
			(at 0 0.889 270)
			(size 0.508 0.508)
			(layers "F.Cu" "F.Mask" "F.Paste")
			(net "GND")
		)
		(zone
			(layer "F.Cu")
			(hatch none 0.5)
			(connect_pads
				(clearance 0)
			)
			(min_thickness 0.25)
			(keepout
				(tracks not_allowed)
				(vias allowed)
				(pads allowed)
				(copperpour not_allowed)
				(footprints allowed)
			)
			(placement
				(enabled no)
				(sheetname "")
			)
			(fill
				(thermal_gap 0.5)
				(thermal_bridge_width 0.5)
				(island_removal_mode 0)
			)
			(polygon
				(pts
					(xy 346.964 -94.015306) (xy 346.964 -93.507306) (xy 347.345 -93.507306) (xy 347.345 -94.015306)
				)
			)
		)
		(zone
			(layer "F.Cu")
			(hatch none 0.5)
			(connect_pads
				(clearance 0)
			)
			(min_thickness 0.25)
			(keepout
				(tracks allowed)
				(vias not_allowed)
				(pads allowed)
				(copperpour not_allowed)
				(footprints allowed)
			)
			(placement
				(enabled no)
				(sheetname "")
			)
			(fill
				(thermal_gap 0.5)
				(thermal_bridge_width 0.5)
				(island_removal_mode 0)
			)
			(polygon
				(pts
					(xy 347.345 -94.015306) (xy 347.345 -93.507306) (xy 346.964 -93.507306) (xy 346.964 -94.015306)
				)
			)
		)
	)
)
